(kicad_pcb
	(version 20260206)
	(generator "pcbnew")
	(generator_version "10.0")
	(general
		(thickness 1.6)
		(legacy_teardrops no)
	)
	(paper "A4")
	(title_block
		(title "04192023_DAF0TMB3IC0_F0TG_MB_C_brd_V02_OCP.brd")
		(comment 1 "Grand Teton / footprint 2417 of 8354 (U6015), pads 112-223 of 354")
	)
	(layers
		(0 "F.Cu" signal "TOP")
		(4 "In1.Cu" signal "GND")
		(6 "In2.Cu" signal "IN1")
		(8 "In3.Cu" signal "GND1")
		(10 "In4.Cu" signal "IN2")
		(12 "In5.Cu" signal "GND2")
		(14 "In6.Cu" signal "IN3")
		(16 "In7.Cu" signal "GND3")
		(18 "In8.Cu" signal "VCC")
		(20 "In9.Cu" signal "VCC1")
		(22 "In10.Cu" signal "GND4")
		(24 "In11.Cu" signal "IN4")
		(26 "In12.Cu" signal "GND5")
		(28 "In13.Cu" signal "IN5")
		(30 "In14.Cu" signal "GND6")
		(32 "In15.Cu" signal "IN6")
		(34 "In16.Cu" signal "GND7")
		(2 "B.Cu" signal "BOTTOM")
		(9 "F.Adhes" user "F.Adhesive")
		(11 "B.Adhes" user "B.Adhesive")
		(13 "F.Paste" user "Package Geometry/Pastemask Top")
		(15 "B.Paste" user "Package Geometry/Pastemask Bottom")
		(5 "F.SilkS" user "Ref Des/Silkscreen Top")
		(7 "B.SilkS" user "Ref Des/Silkscreen Bottom")
		(1 "F.Mask" user "Board Geometry/Soldermask Top")
		(3 "B.Mask" user "Board Geometry/Soldermask Bottom")
		(17 "Dwgs.User" user "User.Drawings")
		(19 "Cmts.User" user "User.Comments")
		(21 "Eco1.User" user "User.Eco1")
		(23 "Eco2.User" user "User.Eco2")
		(25 "Edge.Cuts" user "Board Geometry/Outline")
		(27 "Margin" user)
		(31 "F.CrtYd" user "Package Geometry/Place Bound Top")
		(29 "B.CrtYd" user "Package Geometry/Place Bound Bottom")
		(35 "F.Fab" user "Ref Des/Assembly Top")
		(33 "B.Fab" user "Ref Des/Assembly Bottom")
	)
	(footprint ""
		(layer "F.Cu")
		(at 88.995758 -387.342634)
		(property "Reference" "U6015"
			(at -7.723124 -7.528052 0)
			(unlocked yes)
			(layer "F.SilkS")
			(effects
				(font
					(size 0.7874 0.5842)
					(thickness 0.1524)
				)
				(justify left)
			)
		)
		(property "Value" ""
			(at 0 0 0)
			(layer "F.Fab")
			(effects
				(font
					(size 1.27 1.27)
				)
			)
		)
		(duplicate_pad_numbers_are_jumpers no)
		(pad "BV32" smd circle
			(at 1.20269 2.724912)
			(size 0.381 0.381)
			(layers "F.Cu" "F.Mask" "F.Paste")
			(net "GND")
		)
		(pad "BW2" smd circle
			(at 1.150112 -3.41884)
			(size 0.3048 0.3048)
			(layers "F.Cu" "F.Mask" "F.Paste")
			(net "GND")
		)
		(pad "BW34" smd circle
			(at 1.150112 3.420364)
			(size 0.3048 0.3048)
			(layers "F.Cu" "F.Mask" "F.Paste")
			(net "GND")
		)
		(pad "BY1" smd oval
			(at 0.849884 -3.938524)
			(size 0.254 0.3302)
			(layers "F.Cu" "F.Mask" "F.Paste")
			(net "GND")
		)
		(pad "BY35" smd oval
			(at 0.849884 3.940048)
			(size 0.254 0.3302)
			(layers "F.Cu" "F.Mask" "F.Paste")
			(net "GND")
		)
		(pad "C2" smd circle
			(at 10.750042 -3.41884)
			(size 0.3048 0.3048)
			(layers "F.Cu" "F.Mask" "F.Paste")
			(net "NCF_CPU1_P1_GND")
		)
		(pad "C34" smd circle
			(at 10.750042 3.420364)
			(size 0.3048 0.3048)
			(layers "F.Cu" "F.Mask" "F.Paste")
			(net "NCF_CPU1_P1_GND")
		)
		(pad "CA7" smd circle
			(at 0.80264 -2.12471)
			(size 0.381 0.381)
			(layers "F.Cu" "F.Mask" "F.Paste")
			(net "P5E_CPU1_P1_TX_BUF_DP<8>")
		)
		(pad "CA26" smd circle
			(at 0.80264 1.339342)
			(size 0.381 0.381)
			(layers "F.Cu" "F.Mask" "F.Paste")
			(net "P5E_CPU1_P1_RX_DP<8>")
		)
		(pad "CB2" smd circle
			(at 0.54991 -3.41884)
			(size 0.3048 0.3048)
			(layers "F.Cu" "F.Mask" "F.Paste")
			(net "P5E_CPU1_P1_RX_BUF_DN<8>")
		)
		(pad "CB34" smd circle
			(at 0.54991 3.420364)
			(size 0.3048 0.3048)
			(layers "F.Cu" "F.Mask" "F.Paste")
			(net "P5E_CPU1_P1_TX_C_DN<8>")
		)
		(pad "CC10" smd circle
			(at 0.40259 -1.431798)
			(size 0.381 0.381)
			(layers "F.Cu" "F.Mask" "F.Paste")
			(net "P5E_CPU1_P1_TX_BUF_DN<8>")
		)
		(pad "CC29" smd circle
			(at 0.40259 2.032254)
			(size 0.381 0.381)
			(layers "F.Cu" "F.Mask" "F.Paste")
			(net "P5E_CPU1_P1_RX_DN<8>")
		)
		(pad "CD1" smd oval
			(at 0.249936 -3.938524)
			(size 0.254 0.3302)
			(layers "F.Cu" "F.Mask" "F.Paste")
			(net "P5E_CPU1_P1_RX_BUF_DP<8>")
		)
		(pad "CD35" smd oval
			(at 0.249936 3.940048)
			(size 0.254 0.3302)
			(layers "F.Cu" "F.Mask" "F.Paste")
			(net "P5E_CPU1_P1_TX_C_DP<8>")
		)
		(pad "CE4" smd circle
			(at 0.00254 -2.817368)
			(size 0.381 0.381)
			(layers "F.Cu" "F.Mask" "F.Paste")
			(net "GND")
		)
		(pad "CE13" smd circle
			(at 0.00254 -0.79629)
			(size 0.3048 0.3048)
			(layers "F.Cu" "F.Mask" "F.Paste")
			(net "GND")
		)
		(pad "CE17" smd circle
			(at 0.00254 -0.296164)
			(size 0.3048 0.3048)
			(layers "F.Cu" "F.Mask" "F.Paste")
			(net "P1V8_CPU1_RT1_1A")
		)
		(pad "CE20" smd circle
			(at 0.00254 0.203708)
			(size 0.3048 0.3048)
			(layers "F.Cu" "F.Mask" "F.Paste")
			(net "P1V8_CPU1_RT1_1A")
		)
		(pad "CE22" smd circle
			(at 0.00254 0.703834)
			(size 0.3048 0.3048)
			(layers "F.Cu" "F.Mask" "F.Paste")
			(net "GND")
		)
		(pad "CE32" smd circle
			(at 0.00254 2.724912)
			(size 0.381 0.381)
			(layers "F.Cu" "F.Mask" "F.Paste")
			(net "GND")
		)
		(pad "CF2" smd circle
			(at -0.050038 -3.41884)
			(size 0.3048 0.3048)
			(layers "F.Cu" "F.Mask" "F.Paste")
			(net "GND")
		)
		(pad "CF34" smd circle
			(at -0.050038 3.420364)
			(size 0.3048 0.3048)
			(layers "F.Cu" "F.Mask" "F.Paste")
			(net "GND")
		)
		(pad "CG1" smd oval
			(at -0.350012 -3.938524)
			(size 0.254 0.3302)
			(layers "F.Cu" "F.Mask" "F.Paste")
			(net "GND")
		)
		(pad "CG35" smd oval
			(at -0.350012 3.940048)
			(size 0.254 0.3302)
			(layers "F.Cu" "F.Mask" "F.Paste")
			(net "GND")
		)
		(pad "CH7" smd circle
			(at -0.39751 -2.12471)
			(size 0.381 0.381)
			(layers "F.Cu" "F.Mask" "F.Paste")
			(net "P5E_CPU1_P1_TX_BUF_DP<7>")
		)
		(pad "CH26" smd circle
			(at -0.39751 1.339342)
			(size 0.381 0.381)
			(layers "F.Cu" "F.Mask" "F.Paste")
			(net "P5E_CPU1_P1_RX_DP<7>")
		)
		(pad "CJ2" smd circle
			(at -0.649986 -3.41884)
			(size 0.3048 0.3048)
			(layers "F.Cu" "F.Mask" "F.Paste")
			(net "P5E_CPU1_P1_RX_BUF_DN<7>")
		)
		(pad "CJ34" smd circle
			(at -0.649986 3.420364)
			(size 0.3048 0.3048)
			(layers "F.Cu" "F.Mask" "F.Paste")
			(net "P5E_CPU1_P1_TX_C_DN<7>")
		)
		(pad "CK10" smd circle
			(at -0.797306 -1.431798)
			(size 0.381 0.381)
			(layers "F.Cu" "F.Mask" "F.Paste")
			(net "P5E_CPU1_P1_TX_BUF_DN<7>")
		)
		(pad "CK29" smd circle
			(at -0.797306 2.032254)
			(size 0.381 0.381)
			(layers "F.Cu" "F.Mask" "F.Paste")
			(net "P5E_CPU1_P1_RX_DN<7>")
		)
		(pad "CL1" smd oval
			(at -0.94996 -3.938524)
			(size 0.254 0.3302)
			(layers "F.Cu" "F.Mask" "F.Paste")
			(net "P5E_CPU1_P1_RX_BUF_DP<7>")
		)
		(pad "CL35" smd oval
			(at -0.94996 3.940048)
			(size 0.254 0.3302)
			(layers "F.Cu" "F.Mask" "F.Paste")
			(net "P5E_CPU1_P1_TX_C_DP<7>")
		)
		(pad "CM4" smd circle
			(at -1.197356 -2.817368)
			(size 0.381 0.381)
			(layers "F.Cu" "F.Mask" "F.Paste")
			(net "GND")
		)
		(pad "CM13" smd circle
			(at -1.197356 -0.79629)
			(size 0.3048 0.3048)
			(layers "F.Cu" "F.Mask" "F.Paste")
			(net "GND")
		)
		(pad "CM17" smd circle
			(at -1.197356 -0.296164)
			(size 0.3048 0.3048)
			(layers "F.Cu" "F.Mask" "F.Paste")
			(net "P1V8_CPU1_RT1_1A")
		)
		(pad "CM20" smd circle
			(at -1.197356 0.203708)
			(size 0.3048 0.3048)
			(layers "F.Cu" "F.Mask" "F.Paste")
			(net "P1V8_CPU1_RT1_1A")
		)
		(pad "CM22" smd circle
			(at -1.197356 0.703834)
			(size 0.3048 0.3048)
			(layers "F.Cu" "F.Mask" "F.Paste")
			(net "GND")
		)
		(pad "CM32" smd circle
			(at -1.197356 2.724912)
			(size 0.381 0.381)
			(layers "F.Cu" "F.Mask" "F.Paste")
			(net "GND")
		)
		(pad "CN2" smd circle
			(at -1.249934 -3.41884)
			(size 0.3048 0.3048)
			(layers "F.Cu" "F.Mask" "F.Paste")
			(net "GND")
		)
		(pad "CN34" smd circle
			(at -1.249934 3.420364)
			(size 0.3048 0.3048)
			(layers "F.Cu" "F.Mask" "F.Paste")
			(net "GND")
		)
		(pad "CP1" smd oval
			(at -1.549908 -3.938524)
			(size 0.254 0.3302)
			(layers "F.Cu" "F.Mask" "F.Paste")
			(net "GND")
		)
		(pad "CP35" smd oval
			(at -1.549908 3.940048)
			(size 0.254 0.3302)
			(layers "F.Cu" "F.Mask" "F.Paste")
			(net "GND")
		)
		(pad "CR7" smd circle
			(at -1.597406 -2.12471)
			(size 0.381 0.381)
			(layers "F.Cu" "F.Mask" "F.Paste")
			(net "P5E_CPU1_P1_TX_BUF_DP<6>")
		)
		(pad "CR26" smd circle
			(at -1.597406 1.339342)
			(size 0.381 0.381)
			(layers "F.Cu" "F.Mask" "F.Paste")
			(net "P5E_CPU1_P1_RX_DP<6>")
		)
		(pad "CT2" smd circle
			(at -1.849882 -3.41884)
			(size 0.3048 0.3048)
			(layers "F.Cu" "F.Mask" "F.Paste")
			(net "P5E_CPU1_P1_RX_BUF_DN<6>")
		)
		(pad "CT34" smd circle
			(at -1.849882 3.420364)
			(size 0.3048 0.3048)
			(layers "F.Cu" "F.Mask" "F.Paste")
			(net "P5E_CPU1_P1_TX_C_DN<6>")
		)
		(pad "CU10" smd circle
			(at -1.997456 -1.431798)
			(size 0.381 0.381)
			(layers "F.Cu" "F.Mask" "F.Paste")
			(net "P5E_CPU1_P1_TX_BUF_DN<6>")
		)
		(pad "CU29" smd circle
			(at -1.997456 2.032254)
			(size 0.381 0.381)
			(layers "F.Cu" "F.Mask" "F.Paste")
			(net "P5E_CPU1_P1_RX_DN<6>")
		)
		(pad "CV1" smd oval
			(at -2.15011 -3.938524)
			(size 0.254 0.3302)
			(layers "F.Cu" "F.Mask" "F.Paste")
			(net "P5E_CPU1_P1_RX_BUF_DP<6>")
		)
		(pad "CV35" smd oval
			(at -2.15011 3.940048)
			(size 0.254 0.3302)
			(layers "F.Cu" "F.Mask" "F.Paste")
			(net "P5E_CPU1_P1_TX_C_DP<6>")
		)
		(pad "CW4" smd circle
			(at -2.397506 -2.817368)
			(size 0.381 0.381)
			(layers "F.Cu" "F.Mask" "F.Paste")
			(net "GND")
		)
		(pad "CW13" smd circle
			(at -2.397506 -0.79629)
			(size 0.3048 0.3048)
			(layers "F.Cu" "F.Mask" "F.Paste")
			(net "GND")
		)
		(pad "CW17" smd circle
			(at -2.397506 -0.296164)
			(size 0.3048 0.3048)
			(layers "F.Cu" "F.Mask" "F.Paste")
			(net "P0V9_CPU1_RT_2D")
		)
		(pad "CW20" smd circle
			(at -2.397506 0.203708)
			(size 0.3048 0.3048)
			(layers "F.Cu" "F.Mask" "F.Paste")
			(net "P0V9_CPU1_RT_2D")
		)
		(pad "CW22" smd circle
			(at -2.397506 0.703834)
			(size 0.3048 0.3048)
			(layers "F.Cu" "F.Mask" "F.Paste")
			(net "GND")
		)
		(pad "CW32" smd circle
			(at -2.397506 2.724912)
			(size 0.381 0.381)
			(layers "F.Cu" "F.Mask" "F.Paste")
			(net "GND")
		)
		(pad "CY2" smd circle
			(at -2.450084 -3.41884)
			(size 0.3048 0.3048)
			(layers "F.Cu" "F.Mask" "F.Paste")
			(net "GND")
		)
		(pad "CY34" smd circle
			(at -2.450084 3.420364)
			(size 0.3048 0.3048)
			(layers "F.Cu" "F.Mask" "F.Paste")
			(net "GND")
		)
		(pad "D1" smd oval
			(at 10.450068 -3.938524)
			(size 0.254 0.3302)
			(layers "F.Cu" "F.Mask" "F.Paste")
			(net "NCF_CPU1_P1_GND")
		)
		(pad "D35" smd oval
			(at 10.450068 3.940048)
			(size 0.254 0.3302)
			(layers "F.Cu" "F.Mask" "F.Paste")
			(net "NCF_CPU1_P1_GND")
		)
		(pad "DA1" smd oval
			(at -2.750058 -3.938524)
			(size 0.254 0.3302)
			(layers "F.Cu" "F.Mask" "F.Paste")
			(net "GND")
		)
		(pad "DA35" smd oval
			(at -2.750058 3.940048)
			(size 0.254 0.3302)
			(layers "F.Cu" "F.Mask" "F.Paste")
			(net "GND")
		)
		(pad "DB7" smd circle
			(at -2.797302 -2.12471)
			(size 0.381 0.381)
			(layers "F.Cu" "F.Mask" "F.Paste")
			(net "P5E_CPU1_P1_TX_BUF_DP<5>")
		)
		(pad "DB26" smd circle
			(at -2.797302 1.339342)
			(size 0.381 0.381)
			(layers "F.Cu" "F.Mask" "F.Paste")
			(net "P5E_CPU1_P1_RX_DP<5>")
		)
		(pad "DC2" smd circle
			(at -3.050032 -3.41884)
			(size 0.3048 0.3048)
			(layers "F.Cu" "F.Mask" "F.Paste")
			(net "P5E_CPU1_P1_RX_BUF_DN<5>")
		)
		(pad "DC34" smd circle
			(at -3.050032 3.420364)
			(size 0.3048 0.3048)
			(layers "F.Cu" "F.Mask" "F.Paste")
			(net "P5E_CPU1_P1_TX_C_DN<5>")
		)
		(pad "DD10" smd circle
			(at -3.197352 -1.431798)
			(size 0.381 0.381)
			(layers "F.Cu" "F.Mask" "F.Paste")
			(net "P5E_CPU1_P1_TX_BUF_DN<5>")
		)
		(pad "DD29" smd circle
			(at -3.197352 2.032254)
			(size 0.381 0.381)
			(layers "F.Cu" "F.Mask" "F.Paste")
			(net "P5E_CPU1_P1_RX_DN<5>")
		)
		(pad "DE1" smd oval
			(at -3.350006 -3.938524)
			(size 0.254 0.3302)
			(layers "F.Cu" "F.Mask" "F.Paste")
			(net "P5E_CPU1_P1_RX_BUF_DP<5>")
		)
		(pad "DE35" smd oval
			(at -3.350006 3.940048)
			(size 0.254 0.3302)
			(layers "F.Cu" "F.Mask" "F.Paste")
			(net "P5E_CPU1_P1_TX_C_DP<5>")
		)
		(pad "DF4" smd circle
			(at -3.597402 -2.817368)
			(size 0.381 0.381)
			(layers "F.Cu" "F.Mask" "F.Paste")
			(net "GND")
		)
		(pad "DF13" smd circle
			(at -3.597402 -0.79629)
			(size 0.3048 0.3048)
			(layers "F.Cu" "F.Mask" "F.Paste")
			(net "GND")
		)
		(pad "DF17" smd circle
			(at -3.597402 -0.296164)
			(size 0.3048 0.3048)
			(layers "F.Cu" "F.Mask" "F.Paste")
			(net "P0V9_CPU1_RT1_2A_2D")
		)
		(pad "DF20" smd circle
			(at -3.597402 0.203708)
			(size 0.3048 0.3048)
			(layers "F.Cu" "F.Mask" "F.Paste")
			(net "P0V9_CPU1_RT1_2A_2D")
		)
		(pad "DF22" smd circle
			(at -3.597402 0.703834)
			(size 0.3048 0.3048)
			(layers "F.Cu" "F.Mask" "F.Paste")
			(net "GND")
		)
		(pad "DF32" smd circle
			(at -3.597402 2.724912)
			(size 0.381 0.381)
			(layers "F.Cu" "F.Mask" "F.Paste")
			(net "GND")
		)
		(pad "DG2" smd circle
			(at -3.64998 -3.41884)
			(size 0.3048 0.3048)
			(layers "F.Cu" "F.Mask" "F.Paste")
			(net "GND")
		)
		(pad "DG34" smd circle
			(at -3.64998 3.420364)
			(size 0.3048 0.3048)
			(layers "F.Cu" "F.Mask" "F.Paste")
			(net "GND")
		)
		(pad "DH1" smd oval
			(at -3.949954 -3.938524)
			(size 0.254 0.3302)
			(layers "F.Cu" "F.Mask" "F.Paste")
			(net "GND")
		)
		(pad "DH35" smd oval
			(at -3.949954 3.940048)
			(size 0.254 0.3302)
			(layers "F.Cu" "F.Mask" "F.Paste")
			(net "GND")
		)
		(pad "DJ7" smd circle
			(at -3.997452 -2.12471)
			(size 0.381 0.381)
			(layers "F.Cu" "F.Mask" "F.Paste")
			(net "P5E_CPU1_P1_TX_BUF_DP<4>")
		)
		(pad "DJ26" smd circle
			(at -3.997452 1.339342)
			(size 0.381 0.381)
			(layers "F.Cu" "F.Mask" "F.Paste")
			(net "P5E_CPU1_P1_RX_DP<4>")
		)
		(pad "DK2" smd circle
			(at -4.249928 -3.41884)
			(size 0.3048 0.3048)
			(layers "F.Cu" "F.Mask" "F.Paste")
			(net "P5E_CPU1_P1_RX_BUF_DN<4>")
		)
		(pad "DK34" smd circle
			(at -4.249928 3.420364)
			(size 0.3048 0.3048)
			(layers "F.Cu" "F.Mask" "F.Paste")
			(net "P5E_CPU1_P1_TX_C_DN<4>")
		)
		(pad "DL10" smd circle
			(at -4.397502 -1.431798)
			(size 0.381 0.381)
			(layers "F.Cu" "F.Mask" "F.Paste")
			(net "P5E_CPU1_P1_TX_BUF_DN<4>")
		)
		(pad "DL29" smd circle
			(at -4.397502 2.032254)
			(size 0.381 0.381)
			(layers "F.Cu" "F.Mask" "F.Paste")
			(net "P5E_CPU1_P1_RX_DN<4>")
		)
		(pad "DM1" smd oval
			(at -4.549902 -3.938524)
			(size 0.254 0.3302)
			(layers "F.Cu" "F.Mask" "F.Paste")
			(net "P5E_CPU1_P1_RX_BUF_DP<4>")
		)
		(pad "DM35" smd oval
			(at -4.549902 3.940048)
			(size 0.254 0.3302)
			(layers "F.Cu" "F.Mask" "F.Paste")
			(net "P5E_CPU1_P1_TX_C_DP<4>")
		)
		(pad "DN4" smd circle
			(at -4.797298 -2.817368)
			(size 0.381 0.381)
			(layers "F.Cu" "F.Mask" "F.Paste")
			(net "GND")
		)
		(pad "DN13" smd circle
			(at -4.797298 -0.79629)
			(size 0.3048 0.3048)
			(layers "F.Cu" "F.Mask" "F.Paste")
			(net "GND")
		)
		(pad "DN17" smd circle
			(at -4.797298 -0.296164)
			(size 0.3048 0.3048)
			(layers "F.Cu" "F.Mask" "F.Paste")
			(net "P0V9_CPU1_RT1_2A")
		)
		(pad "DN20" smd circle
			(at -4.797298 0.203708)
			(size 0.3048 0.3048)
			(layers "F.Cu" "F.Mask" "F.Paste")
			(net "P0V9_CPU1_RT1_2A")
		)
		(pad "DN22" smd circle
			(at -4.797298 0.703834)
			(size 0.3048 0.3048)
			(layers "F.Cu" "F.Mask" "F.Paste")
			(net "GND")
		)
		(pad "DN32" smd circle
			(at -4.797298 2.724912)
			(size 0.381 0.381)
			(layers "F.Cu" "F.Mask" "F.Paste")
			(net "GND")
		)
		(pad "DP2" smd circle
			(at -4.849876 -3.41884)
			(size 0.3048 0.3048)
			(layers "F.Cu" "F.Mask" "F.Paste")
			(net "GND")
		)
		(pad "DP34" smd circle
			(at -4.849876 3.420364)
			(size 0.3048 0.3048)
			(layers "F.Cu" "F.Mask" "F.Paste")
			(net "GND")
		)
		(pad "DR1" smd oval
			(at -5.150104 -3.938524)
			(size 0.254 0.3302)
			(layers "F.Cu" "F.Mask" "F.Paste")
			(net "GND")
		)
		(pad "DR35" smd oval
			(at -5.150104 3.940048)
			(size 0.254 0.3302)
			(layers "F.Cu" "F.Mask" "F.Paste")
			(net "GND")
		)
		(pad "DT7" smd circle
			(at -5.197348 -2.12471)
			(size 0.381 0.381)
			(layers "F.Cu" "F.Mask" "F.Paste")
			(net "P5E_CPU1_P1_TX_BUF_DP<3>")
		)
		(pad "DT26" smd circle
			(at -5.197348 1.339342)
			(size 0.381 0.381)
			(layers "F.Cu" "F.Mask" "F.Paste")
			(net "P5E_CPU1_P1_RX_DP<3>")
		)
		(pad "DU2" smd circle
			(at -5.450078 -3.41884)
			(size 0.3048 0.3048)
			(layers "F.Cu" "F.Mask" "F.Paste")
			(net "P5E_CPU1_P1_RX_BUF_DN<3>")
		)
		(pad "DU34" smd circle
			(at -5.450078 3.420364)
			(size 0.3048 0.3048)
			(layers "F.Cu" "F.Mask" "F.Paste")
			(net "P5E_CPU1_P1_TX_C_DN<3>")
		)
		(pad "DV10" smd circle
			(at -5.597398 -1.431798)
			(size 0.381 0.381)
			(layers "F.Cu" "F.Mask" "F.Paste")
			(net "P5E_CPU1_P1_TX_BUF_DN<3>")
		)
		(pad "DV29" smd circle
			(at -5.597398 2.032254)
			(size 0.381 0.381)
			(layers "F.Cu" "F.Mask" "F.Paste")
			(net "P5E_CPU1_P1_RX_DN<3>")
		)
		(pad "DW1" smd oval
			(at -5.750052 -3.938524)
			(size 0.254 0.3302)
			(layers "F.Cu" "F.Mask" "F.Paste")
			(net "P5E_CPU1_P1_RX_BUF_DP<3>")
		)
		(pad "DW35" smd oval
			(at -5.750052 3.940048)
			(size 0.254 0.3302)
			(layers "F.Cu" "F.Mask" "F.Paste")
			(net "P5E_CPU1_P1_TX_C_DP<3>")
		)
		(pad "DY4" smd circle
			(at -5.997448 -2.817368)
			(size 0.381 0.381)
			(layers "F.Cu" "F.Mask" "F.Paste")
			(net "GND")
		)
		(pad "DY13" smd circle
			(at -5.997448 -0.79629)
			(size 0.3048 0.3048)
			(layers "F.Cu" "F.Mask" "F.Paste")
			(net "GND")
		)
		(pad "DY17" smd circle
			(at -5.997448 -0.296164)
			(size 0.3048 0.3048)
			(layers "F.Cu" "F.Mask" "F.Paste")
			(net "P0V9_CPU1_RT1_2A")
		)
		(pad "DY20" smd circle
			(at -5.997448 0.203708)
			(size 0.3048 0.3048)
			(layers "F.Cu" "F.Mask" "F.Paste")
			(net "P0V9_CPU1_RT1_2A")
		)
		(pad "DY22" smd circle
			(at -5.997448 0.703834)
			(size 0.3048 0.3048)
			(layers "F.Cu" "F.Mask" "F.Paste")
			(net "GND")
		)
	)
)
